# TIMECARD (Time Appliance Project (Time Card)) — schematic netlist excerpt (pin names and nets, part order shuffled) for the footprints in the layout excerpt that follows; sources: Cadence DE-HDL packaged netlist, KiCad conversion of R4006-B0001-02_R01.brd

U18  FT4232HL_REEL_QFP64  FT4232HL-REEL  pkg QFP64_394_P0197_V1  page 24
  GND_8  = SG
  OSCI  = UNNAMED_524_CAPACITOR_I7_2
  OSCO  = UNNAMED_524_CAPACITOR_I10_2
  VPHY  = XP3R3V_VPHY
  GND_7  = SG
  REF  = UNNAMED_524_FT4232HLREELQFP64_6
  DM  = R_FT_USB_DM
  DP  = R_FT_USB_DP
  VPLL  = XP3R3V_VPLL
  AGND  = SG
  GND_6  = SG
  VCORE_3  = FT4232_VREGOUT
  TEST  = SG
  \reset*\  = UNNAMED_524_FT4232HLREELQFP64_7
  GND_5  = SG
  ADBUS0  = R_FT4232_TCK
  ADBUS1  = R_FT4232_TDI
  ADBUS2  = R_FT4232_TDO
  ADBUS3  = R_FT4232_TMS
  VCCIO_4  = XP3R3V_FT4232
  ADBUS4  = FT4232_MUX1_SEL
  ADBUS5  = FT4232_MUX2_SEL
  ADBUS6  = FT4232_MUX3_SEL
  ADBUS7  = UNNAMED_524_FT4232HLREELQFP64_I
  GND_4  = SG
  BDBUS0  = R_FT4232_I2C_SCL
  BDBUS1  = R_FT4232_I2C_SDA_OUT
  BDBUS2  = R_FT4232_I2C_SDA_IN
  BDBUS3  = UNNAMED_524_FT4232HLREELQFP64_1
  BDBUS4  = UNNAMED_524_FT4232HLREELQFP64_2
  VCCIO_3  = XP3R3V_FT4232
  BDBUS5  = UNNAMED_524_FT4232HLREELQFP64_3
  BDBUS6  = UNNAMED_524_FT4232HLREELQFP64_4
  BDBUS7  = UNNAMED_524_FT4232HLREELQFP64_5
  GND_3  = SG
  \suspend*\  = NC
  VCORE_2  = FT4232_VREGOUT
  CDBUS0  = R_FT4232_CHC_TX
  CDBUS1  = R_FT4232_CHC_RX
  CDBUS2  = NC
  CDBUS3  = NC
  VCCIO_2  = XP3R3V_FT4232
  CDBUS4  = NC
  CDBUS5  = NC
  CDBUS6  = NC
  CDBUS7  = NC
  GND_2  = SG
  DDBUS0  = R_FT4232_CHD_TX
  VREGOUT  = FT4232_VREGOUT
  VREGIN  = XP3R3V_FT4232
  GND_1  = SG
  DDBUS1  = R_FT4232_CHD_RX
  DDBUS2  = NC
  DDBUS3  = NC
  DDBUS4  = NC
  VCCIO_1  = XP3R3V_FT4232
  DDBUS5  = NC
  DDBUS6  = NC
  DDBUS7  = NC
  \pwren*\  = NC
  EEDATA  = FTDI_EE_DAT
  EECLK  = FTDI_EE_CLK
  EECS  = FTDI_EE_CS
  VCORE_1  = FT4232_VREGOUT

(kicad_pcb
	(version 20260206)
	(generator "pcbnew")
	(generator_version "10.0")
	(general
		(thickness 1.6)
		(legacy_teardrops no)
	)
	(paper "A4")
	(title_block
		(title "timecard-production-celestica-r4006 — R4006-B0001-02_R01.brd")
		(comment 1 "Time Appliance Project (Time Card) / footprint 538 of 1113 (U18), pads 47-64 of 64")
	)
	(layers
		(0 "F.Cu" signal "TOP")
		(4 "In1.Cu" signal "L02_GND1")
		(6 "In2.Cu" signal "L03_SIG1")
		(8 "In3.Cu" signal "L04_GND2")
		(10 "In4.Cu" signal "L05_VCC1")
		(12 "In5.Cu" signal "L06_VCC2")
		(14 "In6.Cu" signal "L07_GND3")
		(16 "In7.Cu" signal "L08_SIG2")
		(18 "In8.Cu" signal "L09_GND4")
		(2 "B.Cu" signal "BOTTOM")
		(9 "F.Adhes" user "F.Adhesive")
		(11 "B.Adhes" user "B.Adhesive")
		(13 "F.Paste" user "Package Geometry/Pastemask Top")
		(15 "B.Paste" user "Package Geometry/Pastemask Bottom")
		(5 "F.SilkS" user "Ref Des/Silkscreen Top")
		(7 "B.SilkS" user "Ref Des/Silkscreen Bottom")
		(1 "F.Mask" user "Board Geometry/Soldermask Top")
		(3 "B.Mask" user "Board Geometry/Soldermask Bottom")
		(17 "Dwgs.User" user "User.Drawings")
		(19 "Cmts.User" user "User.Comments")
		(21 "Eco1.User" user "User.Eco1")
		(23 "Eco2.User" user "User.Eco2")
		(25 "Edge.Cuts" user "Board Geometry/Outline")
		(27 "Margin" user)
		(31 "F.CrtYd" user "Package Geometry/Place Bound Top")
		(29 "B.CrtYd" user "Package Geometry/Place Bound Bottom")
		(35 "F.Fab" user "Ref Des/Assembly Top")
		(33 "B.Fab" user "Ref Des/Assembly Bottom")
	)
	(footprint ""
		(layer "F.Cu")
		(at 28.5242 -85.0646 -90)
		(property "Reference" "U18"
			(at -1.4224 -8.09117 90)
			(unlocked yes)
			(layer "F.SilkS")
			(effects
				(font
					(size 0.7874 0.5842)
					(thickness 0.1524)
				)
			)
		)
		(property "Value" ""
			(at 0 0 270)
			(layer "F.Fab")
			(effects
				(font
					(size 1.27 1.27)
				)
			)
		)
		(property "Device Type" "FT4232HL_REEL_QFP64-G223-10282A"
			(at -0.0127 7.86257 270)
			(unlocked yes)
			(layer "F.Fab")
			(hide yes)
			(effects
				(font
					(size 0.381 0.254)
					(thickness 0.000001)
				)
			)
		)
		(property "User Part Number" "PARTNUM*"
			(at 0.17018 8.41375 270)
			(unlocked yes)
			(layer "Cmts.User")
			(hide yes)
			(effects
				(font
					(size 0.381 0.254)
					(thickness 0.000001)
				)
			)
		)
		(duplicate_pad_numbers_are_jumpers no)
		(pad "47" smd rect
			(at 5.8166 -3.24993)
			(size 0.3048 1.6256)
			(layers "F.Cu" "F.Mask" "F.Paste")
			(net "SG")
		)
		(pad "48" smd rect
			(at 5.8166 -3.750056)
			(size 0.3048 1.6256)
			(layers "F.Cu" "F.Mask" "F.Paste")
			(net "R_FT4232_CHD_TX")
		)
		(pad "49" smd rect
			(at 3.750056 -5.8166 90)
			(size 0.3048 1.6256)
			(layers "F.Cu" "F.Mask" "F.Paste")
			(net "FT4232_VREGOUT")
		)
		(pad "50" smd rect
			(at 3.24993 -5.8166 90)
			(size 0.3048 1.6256)
			(layers "F.Cu" "F.Mask" "F.Paste")
			(net "XP3R3V_FT4232")
		)
		(pad "51" smd rect
			(at 2.750058 -5.8166 90)
			(size 0.3048 1.6256)
			(layers "F.Cu" "F.Mask" "F.Paste")
			(net "SG")
		)
		(pad "52" smd rect
			(at 2.249932 -5.8166 90)
			(size 0.3048 1.6256)
			(layers "F.Cu" "F.Mask" "F.Paste")
			(net "R_FT4232_CHD_RX")
		)
		(pad "53" smd rect
			(at 1.75006 -5.8166 90)
			(size 0.3048 1.6256)
			(layers "F.Cu" "F.Mask" "F.Paste")
			(net "Net_796")
		)
		(pad "54" smd rect
			(at 1.249934 -5.8166 90)
			(size 0.3048 1.6256)
			(layers "F.Cu" "F.Mask" "F.Paste")
			(net "Net_795")
		)
		(pad "55" smd rect
			(at 0.750062 -5.8166 90)
			(size 0.3048 1.6256)
			(layers "F.Cu" "F.Mask" "F.Paste")
			(net "Net_794")
		)
		(pad "56" smd rect
			(at 0.249936 -5.8166 90)
			(size 0.3048 1.6256)
			(layers "F.Cu" "F.Mask" "F.Paste")
			(net "XP3R3V_FT4232")
		)
		(pad "57" smd rect
			(at -0.249936 -5.8166 90)
			(size 0.3048 1.6256)
			(layers "F.Cu" "F.Mask" "F.Paste")
			(net "Net_793")
		)
		(pad "58" smd rect
			(at -0.750062 -5.8166 90)
			(size 0.3048 1.6256)
			(layers "F.Cu" "F.Mask" "F.Paste")
			(net "Net_792")
		)
		(pad "59" smd rect
			(at -1.249934 -5.8166 90)
			(size 0.3048 1.6256)
			(layers "F.Cu" "F.Mask" "F.Paste")
			(net "Net_791")
		)
		(pad "60" smd rect
			(at -1.75006 -5.8166 90)
			(size 0.3048 1.6256)
			(layers "F.Cu" "F.Mask" "F.Paste")
			(net "Net_790")
		)
		(pad "61" smd rect
			(at -2.249932 -5.8166 90)
			(size 0.3048 1.6256)
			(layers "F.Cu" "F.Mask" "F.Paste")
			(net "FTDI_EE_DAT")
		)
		(pad "62" smd rect
			(at -2.750058 -5.8166 90)
			(size 0.3048 1.6256)
			(layers "F.Cu" "F.Mask" "F.Paste")
			(net "FTDI_EE_CLK")
		)
		(pad "63" smd rect
			(at -3.24993 -5.8166 90)
			(size 0.3048 1.6256)
			(layers "F.Cu" "F.Mask" "F.Paste")
			(net "FTDI_EE_CS")
		)
		(pad "64" smd rect
			(at -3.750056 -5.8166 90)
			(size 0.3048 1.6256)
			(layers "F.Cu" "F.Mask" "F.Paste")
			(net "FT4232_VREGOUT")
		)
	)
)
